# Barreleye-G2_Tri-mode BPX24-DVT-X01-SKU-BOM-X07-20171222_Final.xls.xlsx — DEPOP (bom)
| FOXCONN TECHNOLOGY GROUP |  |  |  |  |  |  |  |  |  |  |  |  |
| BILL OF MATERIAL |  |  |  |  |  |  |  |  |  |  |  |  |
| REV OF  BOM | X07 | CUSTOMER | <name> |  | CUSTOMER P/N |  | PRODUCT CODE |  | PWA  REV | X01 | DATE | 43091 |
| Sourcing (Single/Sole/Multi) | Critical Commodity (Y or N) | Component Class (1, 2, other) | Customer PSL (Y or N) | Item Number | Foxconn P/N | Customer P/N | Part Description | Manufacturer  Full Name | Manufacturer  Part Number | Qty | RoHS Status | Location |
|  | Y | 2 | Y(3) | 1 | 620101T02-015-G | - | CAP,100nF,+/-10%,X7R,16V,G,SMD0402 | MURATA ELEC. NORTH AMERICA | GRM155R71C104K | 3 | Y | PSTC13,PFTC13,PETC13 |
|  | ND | ND | Y(4) | 2 | 61010LA00-017-G | - | RES,4.7KOhm,+/-1%,1/16W,G,SMD0402 | KOA SPEER ELECTRONICS, INC. | RK73H1ETTP4701F | 6 | N | PSTR16,PFTR16,PETR16,PSTR3005,PFTR3005,PETR3005 |
|  | N | ND | Y(4) | 3 | 610107A00-017-G | - | RES,0 Ohm,+/-5%,1/16W,G,SMD0402 | KOA SPEER ELECTRONICS, INC. | RK73Z1ETTP | 21 | N | PSRR13,PSTR17,PFTR17,PETR17,R19,R20,R231,R232,R536,R537,R538,R539,R554,R574,R575,R576,R577,R2159,PSTR3014,PFTR3014,PETR3014 |
|  | N |  | Y(5) | 4 | 61100QD00-017-G |  | RES,787 Ohm,+/-0.1%,1/16W,G,SMD0402 | KOA SPEER ELECTRONICS, INC. | RN731ETTP7870B25 | 6 | Y | PSTR18,PFTR18,PETR18,PSTR3015,PFTR3015,PETR3015 |
|  | ND |  | Y(5) | 5 | 61100SU00-017-G |  | RES,105 Ohm,+/-0.1%,1/16W,G,SMD0402 | KOA SPEER ELECTRONICS, INC. | RN731ETTP1050B25 | 3 |  | PSTR19,PFTR19,PETR19 |
|  | ND |  | Y(4) | 6 | 61012JH00-017-G |  | RES,470 Ohm,+/-5%,1/8W,G,SMD0805 | KOA SPEER ELECTRONICS, INC. | RK73B2ATTD471J | 4 | N | PSRR20,PSTR3000,PFTR3000,PETR3000 |
|  | ND | ND | Y(5) | 7 | 61100BP00-017-G |  | RES,3.09KOhm,+/-0.1%,1/16W,G,SMD0402 | KOA SPEER ELECTRONICS, INC. | RN731ETTP3091B25 | 3 | Y | PSTR3006,PFTR3006,PETR3006 |
|  | ND | ND | Y(3) | 8 | 62010QB00-015-G | - | CAP,10nF,+/-10%,X7R,50V,G,SMD0402 | MURATA ELEC. NORTH AMERICA | GRM155R71H103K | 1 | N | PSRC9 |
|  | Y | 2 | Y(4) | 9 | 620105U00-015-G | - | CAP,220pF,+/-10%,X7R,50V,G,SMD0402 | MURATA ELEC. NORTH AMERICA | GRM155R71H221K | 1 | N | PSRC13 |
|  | ND | ND | Y(4) | 10 | 61011HA00-017-G |  | RES,1 Ohm,+/-1%,1/16W,G,SMD0402 | KOA SPEER ELECTRONICS, INC. | RK73H1ETTP1R00F | 1 | N | PSRR14 |
|  | N | Other | N | 11 | 61011MQ00-017-G | - | RES,4.75KOhm,+/-1%,1/16W,G,SMD0402 | KOA SPEER ELECTRONICS, INC. | RK73H1ETTP4751F | 1 | N | R3 |
|  | N | Other | Y(4) | 12 | 61010JY00-017-G | - | RES,220 Ohm,+/-5%,1/16W,G,SMD0402 | KOA SPEER ELECTRONICS, INC. | RK73B1ETTP221J | 9 | N | R11,R13,R1671,R1682,R1686,R1689,R1695,R1699,R1784 |
|  | N | other | Y(4) | 13 | 610100T00-017-G |  | RES,1KOhm,+/-5%,1/16W,G,SMD0402 | KOA SPEER ELECTRONICS, INC. | RK73B1ETTP102J | 10 | N | R520,R563,R2055,R2056,R2057,R2058,R2076,R2078,R2081,R2156 |
|  | N | ND | N | 14 | 610114J00-017-G | - | RES,2KOhm,+/-1%,1/16W,G,SMD0402 | KOA SPEER ELECTRONICS, INC. | RK73H1ETTP2001F | 1 | N | R551 |
|  | N | ND | Y(4) | 15 | 61010L300-017-G | - | RES,1KOhm,+/-1%,1/16W,G,SMD0402 | KOA SPEER ELECTRONICS, INC. | RK73H1ETTP1001F | 4 | N | R1075,R1076,R1441,R1442 |
|  | N | ND | Y(4) | 16 | 610107B00-017-G | K9576 | RES,4.7KOhm,+/-5%,1/16W,G,SMD0402 | KOA SPEER ELECTRONICS, INC. | RK73B1ETTP472J | 11 | N | R1669,R1670,R1676,R1680,R1685,R1696,R1779,R1781,R2059,R2150,R2151 |
|  | ND | ND | Y(5) | 17 | 61100AH00-017-G |  | RES,10KOhm,+/-0.5%,1/16W,G,SMD0402 | KOA SPEER ELECTRONICS, INC. | RN731ETTP1002D25 | 23 | Y | R2053,R2054,R2080,R2088,R2089,R2090,R2091,R2092,R2093,R2094,R2095,R2096,R2097,R2098,R2099,R2100,R2101,R2102,R2103,R2104,R2105,R2106,R2107 |
|  | N | Other | Y(4) | 18 | 61011B300-017-G | - | RES,1MOhm,+/-1%,1/16W,G,SMD0402 | KOA SPEER ELECTRONICS, INC. | RK73H1ETTP1004F | 1 | N | R2087 |
|  | N | Other | N | 19 | 61011BW00-017-G |  | RES,1.2KOhm,+/-1%,1/16W,G,SMD0402 | KOA SPEER ELECTRONICS, INC. | RK73H1ETTP1201F | 1 | N | R2157 |
